# TIMECARD (Time Appliance Project (Time Card)) — schematic netlist excerpt (pin names and nets, part order shuffled) for the footprints in the layout excerpt that follows; sources: Cadence DE-HDL packaged netlist, KiCad conversion of R4006-B0001-02_R01.brd

Y3  OSC6P_V2  pkg SMC_Y6_126X197  page 15
  OE  = CLK_200M_OE
  NC  = NC
  GND  = SG
  OUT_P  = OSC_200M_CLKP
  OUT_N  = OSC_200M_CLKN
  VDD  = VDD3V3_OSC_200M

(kicad_pcb
	(version 20260206)
	(generator "pcbnew")
	(generator_version "10.0")
	(general
		(thickness 1.6)
		(legacy_teardrops no)
	)
	(paper "A4")
	(title_block
		(title "timecard-production-celestica-r4006 — R4006-B0001-02_R01.brd")
		(comment 1 "Time Appliance Project (Time Card) / footprints 652-652 of 1113")
	)
	(layers
		(0 "F.Cu" signal "TOP")
		(4 "In1.Cu" signal "L02_GND1")
		(6 "In2.Cu" signal "L03_SIG1")
		(8 "In3.Cu" signal "L04_GND2")
		(10 "In4.Cu" signal "L05_VCC1")
		(12 "In5.Cu" signal "L06_VCC2")
		(14 "In6.Cu" signal "L07_GND3")
		(16 "In7.Cu" signal "L08_SIG2")
		(18 "In8.Cu" signal "L09_GND4")
		(2 "B.Cu" signal "BOTTOM")
		(9 "F.Adhes" user "F.Adhesive")
		(11 "B.Adhes" user "B.Adhesive")
		(13 "F.Paste" user "Package Geometry/Pastemask Top")
		(15 "B.Paste" user "Package Geometry/Pastemask Bottom")
		(5 "F.SilkS" user "Ref Des/Silkscreen Top")
		(7 "B.SilkS" user "Ref Des/Silkscreen Bottom")
		(1 "F.Mask" user "Board Geometry/Soldermask Top")
		(3 "B.Mask" user "Board Geometry/Soldermask Bottom")
		(17 "Dwgs.User" user "User.Drawings")
		(19 "Cmts.User" user "User.Comments")
		(21 "Eco1.User" user "User.Eco1")
		(23 "Eco2.User" user "User.Eco2")
		(25 "Edge.Cuts" user "Board Geometry/Outline")
		(27 "Margin" user)
		(31 "F.CrtYd" user "Package Geometry/Place Bound Top")
		(29 "B.CrtYd" user "Package Geometry/Place Bound Bottom")
		(35 "F.Fab" user "Ref Des/Assembly Top")
		(33 "B.Fab" user "Ref Des/Assembly Bottom")
	)
	(footprint ""
		(layer "F.Cu")
		(at 110.8456 -21.971 90)
		(property "Reference" "Y3"
			(at -7.02437 0.0254 0)
			(unlocked yes)
			(layer "F.SilkS")
			(effects
				(font
					(size 0.7874 0.5842)
					(thickness 0.1524)
				)
			)
		)
		(property "Value" ""
			(at 0 0 90)
			(layer "F.Fab")
			(effects
				(font
					(size 1.27 1.27)
				)
			)
		)
		(property "User Part Number" "PARTNUM*"
			(at 0 5.10667 90)
			(unlocked yes)
			(layer "Cmts.User")
			(hide yes)
			(effects
				(font
					(size 0.7874 0.5842)
					(thickness 0.1524)
				)
			)
		)
		(property "Device Type" "OSC6P_V2-A130-00003-AW"
			(at 0 3.91287 90)
			(unlocked yes)
			(layer "F.Fab")
			(hide yes)
			(effects
				(font
					(size 0.7874 0.5842)
					(thickness 0.1524)
				)
			)
		)
		(duplicate_pad_numbers_are_jumpers no)
		(fp_line
			(start 1.903984 -2.803906)
			(end 1.903984 2.803906)
			(stroke
				(width 0.1)
				(type default)
			)
			(layer "F.SilkS")
		)
		(fp_line
			(start -1.903984 -2.803906)
			(end 1.903984 -2.803906)
			(stroke
				(width 0.1)
				(type default)
			)
			(layer "F.SilkS")
		)
		(fp_line
			(start 1.903984 2.803906)
			(end -1.903984 2.803906)
			(stroke
				(width 0.1)
				(type default)
			)
			(layer "F.SilkS")
		)
		(fp_line
			(start -1.903984 2.803906)
			(end -1.903984 -2.803906)
			(stroke
				(width 0.1)
				(type default)
			)
			(layer "F.SilkS")
		)
		(fp_rect
			(start 2.157984 -3.057906)
			(end -2.157984 3.057906)
			(stroke
				(width 0)
				(type default)
			)
			(fill no)
			(layer "F.CrtYd")
		)
		(fp_line
			(start 1.649984 -2.549906)
			(end 1.649984 2.549906)
			(stroke
				(width 0.1)
				(type default)
			)
			(layer "F.Fab")
		)
		(fp_line
			(start -1.649984 -2.549906)
			(end 1.649984 -2.549906)
			(stroke
				(width 0.1)
				(type default)
			)
			(layer "F.Fab")
		)
		(fp_line
			(start 1.649984 2.549906)
			(end -1.649984 2.549906)
			(stroke
				(width 0.1)
				(type default)
			)
			(layer "F.Fab")
		)
		(fp_line
			(start -1.649984 2.549906)
			(end -1.649984 -2.549906)
			(stroke
				(width 0.1)
				(type default)
			)
			(layer "F.Fab")
		)
		(fp_text user "1"
			(at -1.69037 -3.1496 0)
			(unlocked yes)
			(layer "F.SilkS")
			(effects
				(font
					(size 0.7874 0.5842)
					(thickness 0.1524)
				)
			)
		)
		(fp_text user "3"
			(at -1.56337 3.3274 0)
			(unlocked yes)
			(layer "F.SilkS")
			(effects
				(font
					(size 0.7874 0.5842)
					(thickness 0.1524)
				)
			)
		)
		(fp_text user "6"
			(at 2.11963 -2.6416 0)
			(unlocked yes)
			(layer "F.Fab")
			(effects
				(font
					(size 0.7874 0.5842)
					(thickness 0.1524)
				)
			)
		)
		(fp_text user "1"
			(at -2.56667 -2.2606 0)
			(unlocked yes)
			(layer "F.Fab")
			(effects
				(font
					(size 0.7874 0.5842)
					(thickness 0.1524)
				)
			)
		)
		(fp_text user "3"
			(at -2.56667 2.1844 0)
			(unlocked yes)
			(layer "F.Fab")
			(effects
				(font
					(size 0.7874 0.5842)
					(thickness 0.1524)
				)
			)
		)
		(fp_text user "4"
			(at 1.49733 2.9464 0)
			(unlocked yes)
			(layer "F.Fab")
			(effects
				(font
					(size 0.7874 0.5842)
					(thickness 0.1524)
				)
			)
		)
		(pad "1" smd rect
			(at -1.050036 -1.27 90)
			(size 0.889 0.635)
			(layers "F.Cu" "F.Mask" "F.Paste")
			(net "CLK_200M_OE")
		)
		(pad "2" smd rect
			(at -1.050036 0 90)
			(size 0.889 0.635)
			(layers "F.Cu" "F.Mask" "F.Paste")
			(net "Net_763")
		)
		(pad "3" smd rect
			(at -1.050036 1.27 90)
			(size 0.889 0.635)
			(layers "F.Cu" "F.Mask" "F.Paste")
			(net "SG")
		)
		(pad "4" smd rect
			(at 1.050036 1.27 90)
			(size 0.889 0.635)
			(layers "F.Cu" "F.Mask" "F.Paste")
			(net "OSC_200M_CLKP")
		)
		(pad "5" smd rect
			(at 1.050036 0 90)
			(size 0.889 0.635)
			(layers "F.Cu" "F.Mask" "F.Paste")
			(net "OSC_200M_CLKN")
		)
		(pad "6" smd rect
			(at 1.050036 -1.27 90)
			(size 0.889 0.635)
			(layers "F.Cu" "F.Mask" "F.Paste")
			(net "VDD3V3_OSC_200M")
		)
		(zone
			(layer "F.Cu")
			(hatch none 0.5)
			(connect_pads
				(clearance 0)
			)
			(min_thickness 0.25)
			(keepout
				(tracks allowed)
				(vias not_allowed)
				(pads allowed)
				(copperpour not_allowed)
				(footprints allowed)
			)
			(placement
				(enabled no)
				(sheetname "")
			)
			(fill
				(thermal_gap 0.5)
				(thermal_bridge_width 0.5)
				(island_removal_mode 0)
			)
			(polygon
				(pts
					(xy 108.295694 -20.321016) (xy 113.395506 -20.321016) (xy 113.395506 -23.620984) (xy 108.295694 -23.620984)
				)
			)
			(polygon
				(pts
					(xy 109.8931 -21.365464) (xy 109.8931 -20.476464) (xy 109.2581 -20.476464) (xy 109.2581 -21.365464)
				)
			)
			(polygon
				(pts
					(xy 109.8931 -23.465536) (xy 109.8931 -22.576536) (xy 109.2581 -22.576536) (xy 109.2581 -23.465536)
				)
			)
			(polygon
				(pts
					(xy 111.1631 -23.465536) (xy 111.1631 -22.576536) (xy 110.5281 -22.576536) (xy 110.5281 -23.465536)
				)
			)
			(polygon
				(pts
					(xy 111.1631 -21.365464) (xy 111.1631 -20.476464) (xy 110.5281 -20.476464) (xy 110.5281 -21.365464)
				)
			)
			(polygon
				(pts
					(xy 112.4331 -21.365464) (xy 112.4331 -20.476464) (xy 111.7981 -20.476464) (xy 111.7981 -21.365464)
				)
			)
			(polygon
				(pts
					(xy 112.4331 -23.465536) (xy 112.4331 -22.576536) (xy 111.7981 -22.576536) (xy 111.7981 -23.465536)
				)
			)
		)
	)
)
